(kicad_pcb
	(version 20260206)
	(generator "pcbnew")
	(generator_version "10.0")
	(general
		(thickness 1.6)
		(legacy_teardrops no)
	)
	(paper "A4")
	(title_block
		(title "Bryce Canyon_IOM_IOC_16318-2_OCP.brd")
		(comment 1 "Bryce Canyon / footprints 997-1003 of 1605")
	)
	(layers
		(0 "F.Cu" signal "TOP")
		(4 "In1.Cu" signal "L2GND")
		(6 "In2.Cu" signal "L3")
		(8 "In3.Cu" signal "L4VCC")
		(10 "In4.Cu" signal "L5VCC")
		(12 "In5.Cu" signal "L6")
		(14 "In6.Cu" signal "L7GND")
		(2 "B.Cu" signal "BOTTOM")
		(9 "F.Adhes" user "F.Adhesive")
		(11 "B.Adhes" user "B.Adhesive")
		(13 "F.Paste" user "Package Geometry/Pastemask Top")
		(15 "B.Paste" user "Package Geometry/Pastemask Bottom")
		(5 "F.SilkS" user "Ref Des/Silkscreen Top")
		(7 "B.SilkS" user "Ref Des/Silkscreen Bottom")
		(1 "F.Mask" user "Board Geometry/Soldermask Top")
		(3 "B.Mask" user "Board Geometry/Soldermask Bottom")
		(17 "Dwgs.User" user "User.Drawings")
		(19 "Cmts.User" user "User.Comments")
		(21 "Eco1.User" user "User.Eco1")
		(23 "Eco2.User" user "User.Eco2")
		(25 "Edge.Cuts" user "Board Geometry/Outline")
		(27 "Margin" user)
		(31 "F.CrtYd" user "Package Geometry/Place Bound Top")
		(29 "B.CrtYd" user "Package Geometry/Place Bound Bottom")
		(35 "F.Fab" user "Ref Des/Assembly Top")
		(33 "B.Fab" user "Ref Des/Assembly Bottom")
	)
	(footprint ""
		(layer "B.Cu")
		(at 53.5686 -135.7122)
		(property "Reference" "R355"
			(at 0 0 0)
			(layer "B.SilkS")
			(hide yes)
			(effects
				(font
					(size 1.27 1.27)
				)
				(justify mirror)
			)
		)
		(property "Value" "4K7R2F-GP"
			(at -0.064008 -3.993896 0)
			(unlocked yes)
			(layer "B.Fab")
			(hide yes)
			(effects
				(font
					(size 1.016 1.016)
					(thickness 0.1524)
				)
				(justify mirror)
			)
		)
		(property "Device Type" "R402H16"
			(at -0.064008 -5.517896 0)
			(unlocked yes)
			(layer "B.Fab")
			(hide yes)
			(effects
				(font
					(size 1.016 1.016)
					(thickness 0.1524)
				)
				(justify mirror)
			)
		)
		(duplicate_pad_numbers_are_jumpers no)
		(fp_line
			(start -0.508 -0.9398)
			(end 0.508 -0.9398)
			(stroke
				(width 0.1524)
				(type default)
			)
			(layer "B.SilkS")
		)
		(fp_line
			(start 0.508 -0.9398)
			(end 0.508 0.9398)
			(stroke
				(width 0.1524)
				(type default)
			)
			(layer "B.SilkS")
		)
		(fp_rect
			(start 0.508 0.9398)
			(end -0.508 -0.9398)
			(stroke
				(width 0)
				(type default)
			)
			(fill no)
			(layer "B.CrtYd")
		)
		(fp_rect
			(start 0.508 0.9398)
			(end -0.508 -0.9398)
			(stroke
				(width 0)
				(type default)
			)
			(fill no)
			(layer "B.Fab")
		)
		(pad "1" smd custom
			(at 0 -0.4445 180)
			(size 0.1397 0.1397)
			(layers "B.Cu" "B.Mask" "B.Paste")
			(net "SLOTID_1")
			(options
				(clearance outline)
				(anchor circle)
			)
			(primitives
				(gr_poly
					(pts
						(arc
							(start -0.1778 0.2794)
							(mid -0.249642 0.249642)
							(end -0.2794 0.1778)
						)
						(arc
							(start -0.2794 -0.1778)
							(mid -0.249642 -0.249642)
							(end -0.1778 -0.2794)
						)
						(arc
							(start 0.1778 -0.2794)
							(mid 0.249642 -0.249642)
							(end 0.2794 -0.1778)
						)
						(arc
							(start 0.2794 0.1778)
							(mid 0.249642 0.249642)
							(end 0.1778 0.2794)
						)
					)
					(width 0)
					(fill yes)
				)
			)
		)
		(pad "2" smd custom
			(at 0 0.4445 180)
			(size 0.1397 0.1397)
			(layers "B.Cu" "B.Mask" "B.Paste")
			(net "GND")
			(options
				(clearance outline)
				(anchor circle)
			)
			(primitives
				(gr_poly
					(pts
						(arc
							(start -0.1778 0.2794)
							(mid -0.249642 0.249642)
							(end -0.2794 0.1778)
						)
						(arc
							(start -0.2794 -0.1778)
							(mid -0.249642 -0.249642)
							(end -0.1778 -0.2794)
						)
						(arc
							(start 0.1778 -0.2794)
							(mid 0.249642 -0.249642)
							(end 0.2794 -0.1778)
						)
						(arc
							(start 0.2794 0.1778)
							(mid 0.249642 0.249642)
							(end 0.1778 0.2794)
						)
					)
					(width 0)
					(fill yes)
				)
			)
		)
	)
	(footprint ""
		(layer "B.Cu")
		(at 78.9178 -142.4686 180)
		(property "Reference" "R127"
			(at 0 0 0)
			(layer "B.SilkS")
			(hide yes)
			(effects
				(font
					(size 1.27 1.27)
				)
				(justify mirror)
			)
		)
		(property "Value" "0R2J-2-GP"
			(at -0.064008 -3.993896 180)
			(unlocked yes)
			(layer "B.Fab")
			(hide yes)
			(effects
				(font
					(size 1.016 1.016)
					(thickness 0.1524)
				)
				(justify mirror)
			)
		)
		(property "Device Type" "R402H16"
			(at -0.064008 -5.517896 180)
			(unlocked yes)
			(layer "B.Fab")
			(hide yes)
			(effects
				(font
					(size 1.016 1.016)
					(thickness 0.1524)
				)
				(justify mirror)
			)
		)
		(duplicate_pad_numbers_are_jumpers no)
		(fp_line
			(start 0.508 -0.9398)
			(end 0.508 0.9398)
			(stroke
				(width 0.1524)
				(type default)
			)
			(layer "B.SilkS")
		)
		(fp_line
			(start -0.508 -0.9398)
			(end 0.508 -0.9398)
			(stroke
				(width 0.1524)
				(type default)
			)
			(layer "B.SilkS")
		)
		(fp_rect
			(start 0.508 0.9398)
			(end -0.508 -0.9398)
			(stroke
				(width 0)
				(type default)
			)
			(fill no)
			(layer "B.CrtYd")
		)
		(fp_rect
			(start 0.508 0.9398)
			(end -0.508 -0.9398)
			(stroke
				(width 0)
				(type default)
			)
			(fill no)
			(layer "B.Fab")
		)
		(pad "1" smd custom
			(at 0 -0.4445)
			(size 0.1397 0.1397)
			(layers "B.Cu" "B.Mask" "B.Paste")
			(net "I2C_EXP_LOC_SCL")
			(options
				(clearance outline)
				(anchor circle)
			)
			(primitives
				(gr_poly
					(pts
						(arc
							(start -0.1778 0.2794)
							(mid -0.249642 0.249642)
							(end -0.2794 0.1778)
						)
						(arc
							(start -0.2794 -0.1778)
							(mid -0.249642 -0.249642)
							(end -0.1778 -0.2794)
						)
						(arc
							(start 0.1778 -0.2794)
							(mid 0.249642 -0.249642)
							(end 0.2794 -0.1778)
						)
						(arc
							(start 0.2794 0.1778)
							(mid 0.249642 0.249642)
							(end 0.1778 0.2794)
						)
					)
					(width 0)
					(fill yes)
				)
			)
		)
		(pad "2" smd custom
			(at 0 0.4445)
			(size 0.1397 0.1397)
			(layers "B.Cu" "B.Mask" "B.Paste")
			(net "I2C_EXP_LOC_SCL_R")
			(options
				(clearance outline)
				(anchor circle)
			)
			(primitives
				(gr_poly
					(pts
						(arc
							(start -0.1778 0.2794)
							(mid -0.249642 0.249642)
							(end -0.2794 0.1778)
						)
						(arc
							(start -0.2794 -0.1778)
							(mid -0.249642 -0.249642)
							(end -0.1778 -0.2794)
						)
						(arc
							(start 0.1778 -0.2794)
							(mid 0.249642 -0.249642)
							(end 0.2794 -0.1778)
						)
						(arc
							(start 0.2794 0.1778)
							(mid 0.249642 0.249642)
							(end 0.1778 0.2794)
						)
					)
					(width 0)
					(fill yes)
				)
			)
		)
	)
	(footprint ""
		(layer "B.Cu")
		(at 44.323 -135.6614 180)
		(property "Reference" "R372"
			(at 0 0 0)
			(layer "B.SilkS")
			(hide yes)
			(effects
				(font
					(size 1.27 1.27)
				)
				(justify mirror)
			)
		)
		(property "Value" "4K7R2F-GP"
			(at -0.064008 -3.993896 180)
			(unlocked yes)
			(layer "B.Fab")
			(hide yes)
			(effects
				(font
					(size 1.016 1.016)
					(thickness 0.1524)
				)
				(justify mirror)
			)
		)
		(property "Device Type" "R402H16"
			(at -0.064008 -5.517896 180)
			(unlocked yes)
			(layer "B.Fab")
			(hide yes)
			(effects
				(font
					(size 1.016 1.016)
					(thickness 0.1524)
				)
				(justify mirror)
			)
		)
		(duplicate_pad_numbers_are_jumpers no)
		(fp_line
			(start 0.508 -0.9398)
			(end 0.508 0.9398)
			(stroke
				(width 0.1524)
				(type default)
			)
			(layer "B.SilkS")
		)
		(fp_line
			(start -0.508 -0.9398)
			(end 0.508 -0.9398)
			(stroke
				(width 0.1524)
				(type default)
			)
			(layer "B.SilkS")
		)
		(fp_rect
			(start 0.508 0.9398)
			(end -0.508 -0.9398)
			(stroke
				(width 0)
				(type default)
			)
			(fill no)
			(layer "B.CrtYd")
		)
		(fp_rect
			(start 0.508 0.9398)
			(end -0.508 -0.9398)
			(stroke
				(width 0)
				(type default)
			)
			(fill no)
			(layer "B.Fab")
		)
		(pad "1" smd custom
			(at 0 -0.4445)
			(size 0.1397 0.1397)
			(layers "B.Cu" "B.Mask" "B.Paste")
			(net "P3V3_STBY")
			(options
				(clearance outline)
				(anchor circle)
			)
			(primitives
				(gr_poly
					(pts
						(arc
							(start -0.1778 0.2794)
							(mid -0.249642 0.249642)
							(end -0.2794 0.1778)
						)
						(arc
							(start -0.2794 -0.1778)
							(mid -0.249642 -0.249642)
							(end -0.1778 -0.2794)
						)
						(arc
							(start 0.1778 -0.2794)
							(mid 0.249642 -0.249642)
							(end 0.2794 -0.1778)
						)
						(arc
							(start 0.2794 0.1778)
							(mid 0.249642 0.249642)
							(end 0.1778 0.2794)
						)
					)
					(width 0)
					(fill yes)
				)
			)
		)
		(pad "2" smd custom
			(at 0 0.4445)
			(size 0.1397 0.1397)
			(layers "B.Cu" "B.Mask" "B.Paste")
			(net "BMC_GPIOS4")
			(options
				(clearance outline)
				(anchor circle)
			)
			(primitives
				(gr_poly
					(pts
						(arc
							(start -0.1778 0.2794)
							(mid -0.249642 0.249642)
							(end -0.2794 0.1778)
						)
						(arc
							(start -0.2794 -0.1778)
							(mid -0.249642 -0.249642)
							(end -0.1778 -0.2794)
						)
						(arc
							(start 0.1778 -0.2794)
							(mid 0.249642 -0.249642)
							(end 0.2794 -0.1778)
						)
						(arc
							(start 0.2794 0.1778)
							(mid 0.249642 0.249642)
							(end 0.1778 0.2794)
						)
					)
					(width 0)
					(fill yes)
				)
			)
		)
	)
	(footprint ""
		(layer "B.Cu")
		(at 38.98773 -140.300964 180)
		(property "Reference" "C97"
			(at 0 0 0)
			(layer "B.SilkS")
			(hide yes)
			(effects
				(font
					(size 1.27 1.27)
				)
				(justify mirror)
			)
		)
		(property "Value" "SC1U16V3KX-5GP"
			(at 0 -2.8194 180)
			(unlocked yes)
			(layer "B.Fab")
			(hide yes)
			(effects
				(font
					(size 1.016 1.016)
					(thickness 0.1524)
				)
				(justify mirror)
			)
		)
		(property "Device Type" "C603H36"
			(at 0 -4.3434 180)
			(unlocked yes)
			(layer "B.Fab")
			(hide yes)
			(effects
				(font
					(size 1.016 1.016)
					(thickness 0.1524)
				)
				(justify mirror)
			)
		)
		(duplicate_pad_numbers_are_jumpers no)
		(fp_line
			(start -0.508 0)
			(end 0.508 0)
			(stroke
				(width 0.2032)
				(type default)
			)
			(layer "B.SilkS")
		)
		(fp_rect
			(start 0.5842 1.3335)
			(end -0.5842 -1.3335)
			(stroke
				(width 0)
				(type default)
			)
			(fill no)
			(layer "B.CrtYd")
		)
		(fp_rect
			(start 0.5842 1.3335)
			(end -0.5842 -1.3335)
			(stroke
				(width 0)
				(type default)
			)
			(fill no)
			(layer "B.Fab")
		)
		(pad "1" smd custom
			(at 0 -0.762)
			(size 0.2159 0.2159)
			(layers "B.Cu" "B.Mask" "B.Paste")
			(net "P3V3_STBY")
			(options
				(clearance outline)
				(anchor circle)
			)
			(primitives
				(gr_poly
					(pts
						(arc
							(start -0.3302 0.4318)
							(mid -0.402042 0.402042)
							(end -0.4318 0.3302)
						)
						(arc
							(start -0.4318 -0.3302)
							(mid -0.402042 -0.402042)
							(end -0.3302 -0.4318)
						)
						(arc
							(start 0.3302 -0.4318)
							(mid 0.402042 -0.402042)
							(end 0.4318 -0.3302)
						)
						(arc
							(start 0.4318 0.3302)
							(mid 0.402042 0.402042)
							(end 0.3302 0.4318)
						)
					)
					(width 0)
					(fill yes)
				)
			)
		)
		(pad "2" smd custom
			(at 0 0.762)
			(size 0.2159 0.2159)
			(layers "B.Cu" "B.Mask" "B.Paste")
			(net "GND")
			(options
				(clearance outline)
				(anchor circle)
			)
			(primitives
				(gr_poly
					(pts
						(arc
							(start -0.3302 0.4318)
							(mid -0.402042 0.402042)
							(end -0.4318 0.3302)
						)
						(arc
							(start -0.4318 -0.3302)
							(mid -0.402042 -0.402042)
							(end -0.3302 -0.4318)
						)
						(arc
							(start 0.3302 -0.4318)
							(mid 0.402042 -0.402042)
							(end 0.4318 -0.3302)
						)
						(arc
							(start 0.4318 0.3302)
							(mid 0.402042 0.402042)
							(end 0.3302 0.4318)
						)
					)
					(width 0)
					(fill yes)
				)
			)
		)
	)
	(footprint ""
		(layer "B.Cu")
		(at 35.007296 -139.330684 180)
		(property "Reference" "C106"
			(at 0 0 0)
			(layer "B.SilkS")
			(hide yes)
			(effects
				(font
					(size 1.27 1.27)
				)
				(justify mirror)
			)
		)
		(property "Value" "SC4D7U25V5KX-1-GP"
			(at 0.0762 -6.1214 180)
			(unlocked yes)
			(layer "B.Fab")
			(hide yes)
			(effects
				(font
					(size 1.016 1.016)
					(thickness 0.1524)
				)
				(justify mirror)
			)
		)
		(property "Device Type" "C805H58"
			(at 0.0762 -8.1534 180)
			(unlocked yes)
			(layer "B.Fab")
			(hide yes)
			(effects
				(font
					(size 1.016 1.016)
					(thickness 0.1524)
				)
				(justify mirror)
			)
		)
		(duplicate_pad_numbers_are_jumpers no)
		(fp_line
			(start -0.635 0)
			(end 0.635 0)
			(stroke
				(width 0.508)
				(type default)
			)
			(layer "B.SilkS")
		)
		(fp_rect
			(start 0.9652 1.778)
			(end -0.9652 -1.778)
			(stroke
				(width 0)
				(type default)
			)
			(fill no)
			(layer "B.CrtYd")
		)
		(fp_poly
			(pts
				(xy 0.9652 -1.778) (xy -0.9652 -1.778) (xy -0.9652 1.778) (xy 0.9652 1.778)
			)
			(stroke
				(width 0)
				(type default)
			)
			(fill no)
			(layer "B.Fab")
		)
		(pad "1" smd rect
			(at 0 -0.9652)
			(size 1.397 1.143)
			(layers "B.Cu" "B.Mask" "B.Paste")
			(net "P3V3_STBY")
		)
		(pad "2" smd rect
			(at 0 0.9652)
			(size 1.397 1.143)
			(layers "B.Cu" "B.Mask" "B.Paste")
			(net "GND")
		)
	)
	(footprint ""
		(layer "B.Cu")
		(at 180.866542 -64.486282 90)
		(property "Reference" "R584"
			(at 0 0 90)
			(layer "B.SilkS")
			(hide yes)
			(effects
				(font
					(size 1.27 1.27)
				)
				(justify mirror)
			)
		)
		(property "Value" "2K2R2F-GP"
			(at -0.064008 -3.993896 90)
			(unlocked yes)
			(layer "B.Fab")
			(hide yes)
			(effects
				(font
					(size 1.016 1.016)
					(thickness 0.1524)
				)
				(justify mirror)
			)
		)
		(property "Device Type" "R402H16"
			(at -0.064008 -5.517896 90)
			(unlocked yes)
			(layer "B.Fab")
			(hide yes)
			(effects
				(font
					(size 1.016 1.016)
					(thickness 0.1524)
				)
				(justify mirror)
			)
		)
		(duplicate_pad_numbers_are_jumpers no)
		(fp_line
			(start 0.508 -0.9398)
			(end 0.508 0.9398)
			(stroke
				(width 0.1524)
				(type default)
			)
			(layer "B.SilkS")
		)
		(fp_line
			(start -0.508 -0.9398)
			(end 0.508 -0.9398)
			(stroke
				(width 0.1524)
				(type default)
			)
			(layer "B.SilkS")
		)
		(fp_rect
			(start 0.508 0.9398)
			(end -0.508 -0.9398)
			(stroke
				(width 0)
				(type default)
			)
			(fill no)
			(layer "B.CrtYd")
		)
		(fp_rect
			(start 0.508 0.9398)
			(end -0.508 -0.9398)
			(stroke
				(width 0)
				(type default)
			)
			(fill no)
			(layer "B.Fab")
		)
		(pad "1" smd custom
			(at 0 -0.4445 270)
			(size 0.1397 0.1397)
			(layers "B.Cu" "B.Mask" "B.Paste")
			(net "P1V8")
			(options
				(clearance outline)
				(anchor circle)
			)
			(primitives
				(gr_poly
					(pts
						(arc
							(start -0.1778 0.2794)
							(mid -0.249642 0.249642)
							(end -0.2794 0.1778)
						)
						(arc
							(start -0.2794 -0.1778)
							(mid -0.249642 -0.249642)
							(end -0.1778 -0.2794)
						)
						(arc
							(start 0.1778 -0.2794)
							(mid 0.249642 -0.249642)
							(end 0.2794 -0.1778)
						)
						(arc
							(start 0.2794 0.1778)
							(mid 0.249642 0.249642)
							(end 0.1778 0.2794)
						)
					)
					(width 0)
					(fill yes)
				)
			)
		)
		(pad "2" smd custom
			(at 0 0.4445 270)
			(size 0.1397 0.1397)
			(layers "B.Cu" "B.Mask" "B.Paste")
			(net "IOC_SCL_3")
			(options
				(clearance outline)
				(anchor circle)
			)
			(primitives
				(gr_poly
					(pts
						(arc
							(start -0.1778 0.2794)
							(mid -0.249642 0.249642)
							(end -0.2794 0.1778)
						)
						(arc
							(start -0.2794 -0.1778)
							(mid -0.249642 -0.249642)
							(end -0.1778 -0.2794)
						)
						(arc
							(start 0.1778 -0.2794)
							(mid 0.249642 -0.249642)
							(end 0.2794 -0.1778)
						)
						(arc
							(start 0.2794 0.1778)
							(mid 0.249642 0.249642)
							(end 0.1778 0.2794)
						)
					)
					(width 0)
					(fill yes)
				)
			)
		)
	)
	(footprint ""
		(layer "B.Cu")
		(at 203.327 -77.978 90)
		(property "Reference" "C377"
			(at 0 0 90)
			(layer "B.SilkS")
			(hide yes)
			(effects
				(font
					(size 1.27 1.27)
				)
				(justify mirror)
			)
		)
		(property "Value" "SCD1U6D3V1KX-GP"
			(at 2.8321 -1.7399 90)
			(unlocked yes)
			(layer "B.Fab")
			(hide yes)
			(effects
				(font
					(size 1.016 1.016)
					(thickness 0.1524)
				)
				(justify mirror)
			)
		)
		(property "Device Type" "C0201H13"
			(at 2.8321 -3.2639 90)
			(unlocked yes)
			(layer "B.Fab")
			(hide yes)
			(effects
				(font
					(size 1.016 1.016)
					(thickness 0.1524)
				)
				(justify mirror)
			)
		)
		(duplicate_pad_numbers_are_jumpers no)
		(fp_rect
			(start 0.2794 0.6477)
			(end -0.2794 -0.6477)
			(stroke
				(width 0)
				(type default)
			)
			(fill no)
			(layer "B.CrtYd")
		)
		(fp_rect
			(start 0.2794 0.6477)
			(end -0.2794 -0.6477)
			(stroke
				(width 0)
				(type default)
			)
			(fill no)
			(layer "B.Fab")
		)
		(pad "1" smd custom
			(at 0 -0.2794 270)
			(size 0.0762 0.0762)
			(layers "B.Cu" "B.Mask" "B.Paste")
			(net "SAS0_AVDD")
			(options
				(clearance outline)
				(anchor circle)
			)
			(primitives
				(gr_poly
					(pts
						(arc
							(start 0.1524 0.127)
							(mid 0.137521 0.162921)
							(end 0.1016 0.1778)
						)
						(arc
							(start -0.1016 0.1778)
							(mid -0.137521 0.162921)
							(end -0.1524 0.127)
						)
						(arc
							(start -0.1524 -0.127)
							(mid -0.137521 -0.162921)
							(end -0.1016 -0.1778)
						)
						(arc
							(start 0.1016 -0.1778)
							(mid 0.137521 -0.162921)
							(end 0.1524 -0.127)
						)
					)
					(width 0)
					(fill yes)
				)
			)
		)
		(pad "2" smd custom
			(at 0 0.2794 270)
			(size 0.0762 0.0762)
			(layers "B.Cu" "B.Mask" "B.Paste")
			(net "GND")
			(options
				(clearance outline)
				(anchor circle)
			)
			(primitives
				(gr_poly
					(pts
						(arc
							(start 0.1524 0.127)
							(mid 0.137521 0.162921)
							(end 0.1016 0.1778)
						)
						(arc
							(start -0.1016 0.1778)
							(mid -0.137521 0.162921)
							(end -0.1524 0.127)
						)
						(arc
							(start -0.1524 -0.127)
							(mid -0.137521 -0.162921)
							(end -0.1016 -0.1778)
						)
						(arc
							(start 0.1016 -0.1778)
							(mid 0.137521 -0.162921)
							(end 0.1524 -0.127)
						)
					)
					(width 0)
					(fill yes)
				)
			)
		)
	)
)
